# T6G (Grand Teton) — schematic netlist excerpt (pin names and nets, part order shuffled) for the footprints in the layout excerpt that follows; sources: Cadence DE-HDL packaged netlist, KiCad conversion of 04192023_DAF0TMB3IC0_F0TG_MB_C_brd_V02_OCP.brd

R813  Q_RES  10K 5% CHIP  pkg 0402LF  page 164 : A = PVDD18_S5_P0 ; B = UART_CPU0_UART0_RX
R2790  Q_RES  0 5% EMPTY  pkg 0402LF  page 234 : A = USB2_HOST_BMC_B_DP ; B = USB2_HOST_BMC_B_BUF_DP

(kicad_pcb
	(version 20260206)
	(generator "pcbnew")
	(generator_version "10.0")
	(general
		(thickness 1.6)
		(legacy_teardrops no)
	)
	(paper "A4")
	(title_block
		(title "04192023_DAF0TMB3IC0_F0TG_MB_C_brd_V02_OCP.brd")
		(comment 1 "Grand Teton / footprints 3915-3916 of 8354")
	)
	(layers
		(0 "F.Cu" signal "TOP")
		(4 "In1.Cu" signal "GND")
		(6 "In2.Cu" signal "IN1")
		(8 "In3.Cu" signal "GND1")
		(10 "In4.Cu" signal "IN2")
		(12 "In5.Cu" signal "GND2")
		(14 "In6.Cu" signal "IN3")
		(16 "In7.Cu" signal "GND3")
		(18 "In8.Cu" signal "VCC")
		(20 "In9.Cu" signal "VCC1")
		(22 "In10.Cu" signal "GND4")
		(24 "In11.Cu" signal "IN4")
		(26 "In12.Cu" signal "GND5")
		(28 "In13.Cu" signal "IN5")
		(30 "In14.Cu" signal "GND6")
		(32 "In15.Cu" signal "IN6")
		(34 "In16.Cu" signal "GND7")
		(2 "B.Cu" signal "BOTTOM")
		(9 "F.Adhes" user "F.Adhesive")
		(11 "B.Adhes" user "B.Adhesive")
		(13 "F.Paste" user "Package Geometry/Pastemask Top")
		(15 "B.Paste" user "Package Geometry/Pastemask Bottom")
		(5 "F.SilkS" user "Ref Des/Silkscreen Top")
		(7 "B.SilkS" user "Ref Des/Silkscreen Bottom")
		(1 "F.Mask" user "Board Geometry/Soldermask Top")
		(3 "B.Mask" user "Board Geometry/Soldermask Bottom")
		(17 "Dwgs.User" user "User.Drawings")
		(19 "Cmts.User" user "User.Comments")
		(21 "Eco1.User" user "User.Eco1")
		(23 "Eco2.User" user "User.Eco2")
		(25 "Edge.Cuts" user "Board Geometry/Outline")
		(27 "Margin" user)
		(31 "F.CrtYd" user "Package Geometry/Place Bound Top")
		(29 "B.CrtYd" user "Package Geometry/Place Bound Bottom")
		(35 "F.Fab" user "Ref Des/Assembly Top")
		(33 "B.Fab" user "Ref Des/Assembly Bottom")
	)
	(footprint ""
		(layer "F.Cu")
		(at 365.701326 -45.267118 -90)
		(property "Reference" "R813"
			(at 0 0 270)
			(layer "F.SilkS")
			(hide yes)
			(effects
				(font
					(size 1.27 1.27)
				)
			)
		)
		(property "Value" ""
			(at 0 0 270)
			(layer "F.Fab")
			(effects
				(font
					(size 1.27 1.27)
				)
			)
		)
		(duplicate_pad_numbers_are_jumpers no)
		(fp_line
			(start -0.7874 0.4064)
			(end -0.7874 -0.4064)
			(stroke
				(width 0.1524)
				(type default)
			)
			(layer "F.SilkS")
		)
		(fp_line
			(start 0.7874 0.4064)
			(end -0.7874 0.4064)
			(stroke
				(width 0.1524)
				(type default)
			)
			(layer "F.SilkS")
		)
		(fp_line
			(start -0.7874 -0.4064)
			(end 0.7874 -0.4064)
			(stroke
				(width 0.1524)
				(type default)
			)
			(layer "F.SilkS")
		)
		(fp_line
			(start 0.7874 -0.4064)
			(end 0.7874 0.4064)
			(stroke
				(width 0.1524)
				(type default)
			)
			(layer "F.SilkS")
		)
		(fp_line
			(start -0.67945 0.3048)
			(end -0.67945 -0.305054)
			(stroke
				(width 0.1)
				(type default)
			)
			(layer "F.Fab")
		)
		(fp_line
			(start -0.12065 0.3048)
			(end -0.67945 0.3048)
			(stroke
				(width 0.1)
				(type default)
			)
			(layer "F.Fab")
		)
		(fp_line
			(start 0.120396 0.3048)
			(end 0.120396 0.2794)
			(stroke
				(width 0.1)
				(type default)
			)
			(layer "F.Fab")
		)
		(fp_line
			(start 0.67945 0.3048)
			(end 0.120396 0.3048)
			(stroke
				(width 0.1)
				(type default)
			)
			(layer "F.Fab")
		)
		(fp_line
			(start -0.12065 0.2794)
			(end -0.12065 0.3048)
			(stroke
				(width 0.1)
				(type default)
			)
			(layer "F.Fab")
		)
		(fp_line
			(start 0.120396 0.2794)
			(end -0.12065 0.2794)
			(stroke
				(width 0.1)
				(type default)
			)
			(layer "F.Fab")
		)
		(fp_line
			(start -0.12065 -0.2794)
			(end 0.12065 -0.2794)
			(stroke
				(width 0.1)
				(type default)
			)
			(layer "F.Fab")
		)
		(fp_line
			(start 0.12065 -0.2794)
			(end 0.12065 -0.3048)
			(stroke
				(width 0.1)
				(type default)
			)
			(layer "F.Fab")
		)
		(fp_line
			(start 0.12065 -0.3048)
			(end 0.67945 -0.3048)
			(stroke
				(width 0.1)
				(type default)
			)
			(layer "F.Fab")
		)
		(fp_line
			(start 0.67945 -0.3048)
			(end 0.67945 0.3048)
			(stroke
				(width 0.1)
				(type default)
			)
			(layer "F.Fab")
		)
		(fp_line
			(start -0.67945 -0.305054)
			(end -0.12065 -0.305054)
			(stroke
				(width 0.1)
				(type default)
			)
			(layer "F.Fab")
		)
		(fp_line
			(start -0.12065 -0.305054)
			(end -0.12065 -0.2794)
			(stroke
				(width 0.1)
				(type default)
			)
			(layer "F.Fab")
		)
		(pad "1" smd circle
			(at -0.40005 0 270)
			(size 0 0)
			(layers "F.Cu" "F.Mask" "F.Paste")
			(net "PVDD18_S5_P0")
		)
		(pad "2" smd circle
			(at 0.40005 0 270)
			(size 0 0)
			(layers "F.Cu" "F.Mask" "F.Paste")
			(net "UART_CPU0_UART0_RX")
		)
	)
	(footprint ""
		(layer "F.Cu")
		(at 15.288006 -105.53573 90)
		(property "Reference" "R2790"
			(at 0 0 90)
			(layer "F.SilkS")
			(hide yes)
			(effects
				(font
					(size 1.27 1.27)
				)
			)
		)
		(property "Value" ""
			(at 0 0 90)
			(layer "F.Fab")
			(effects
				(font
					(size 1.27 1.27)
				)
			)
		)
		(duplicate_pad_numbers_are_jumpers no)
		(fp_line
			(start 0.7874 -0.4064)
			(end 0.7874 0.4064)
			(stroke
				(width 0.1524)
				(type default)
			)
			(layer "F.SilkS")
		)
		(fp_line
			(start -0.7874 -0.4064)
			(end 0.7874 -0.4064)
			(stroke
				(width 0.1524)
				(type default)
			)
			(layer "F.SilkS")
		)
		(fp_line
			(start 0.7874 0.4064)
			(end -0.7874 0.4064)
			(stroke
				(width 0.1524)
				(type default)
			)
			(layer "F.SilkS")
		)
		(fp_line
			(start -0.7874 0.4064)
			(end -0.7874 -0.4064)
			(stroke
				(width 0.1524)
				(type default)
			)
			(layer "F.SilkS")
		)
		(fp_line
			(start -0.12065 -0.305054)
			(end -0.12065 -0.2794)
			(stroke
				(width 0.1)
				(type default)
			)
			(layer "F.Fab")
		)
		(fp_line
			(start -0.67945 -0.305054)
			(end -0.12065 -0.305054)
			(stroke
				(width 0.1)
				(type default)
			)
			(layer "F.Fab")
		)
		(fp_line
			(start 0.67945 -0.3048)
			(end 0.67945 0.3048)
			(stroke
				(width 0.1)
				(type default)
			)
			(layer "F.Fab")
		)
		(fp_line
			(start 0.12065 -0.3048)
			(end 0.67945 -0.3048)
			(stroke
				(width 0.1)
				(type default)
			)
			(layer "F.Fab")
		)
		(fp_line
			(start 0.12065 -0.2794)
			(end 0.12065 -0.3048)
			(stroke
				(width 0.1)
				(type default)
			)
			(layer "F.Fab")
		)
		(fp_line
			(start -0.12065 -0.2794)
			(end 0.12065 -0.2794)
			(stroke
				(width 0.1)
				(type default)
			)
			(layer "F.Fab")
		)
		(fp_line
			(start 0.120396 0.2794)
			(end -0.12065 0.2794)
			(stroke
				(width 0.1)
				(type default)
			)
			(layer "F.Fab")
		)
		(fp_line
			(start -0.12065 0.2794)
			(end -0.12065 0.3048)
			(stroke
				(width 0.1)
				(type default)
			)
			(layer "F.Fab")
		)
		(fp_line
			(start 0.67945 0.3048)
			(end 0.120396 0.3048)
			(stroke
				(width 0.1)
				(type default)
			)
			(layer "F.Fab")
		)
		(fp_line
			(start 0.120396 0.3048)
			(end 0.120396 0.2794)
			(stroke
				(width 0.1)
				(type default)
			)
			(layer "F.Fab")
		)
		(fp_line
			(start -0.12065 0.3048)
			(end -0.67945 0.3048)
			(stroke
				(width 0.1)
				(type default)
			)
			(layer "F.Fab")
		)
		(fp_line
			(start -0.67945 0.3048)
			(end -0.67945 -0.305054)
			(stroke
				(width 0.1)
				(type default)
			)
			(layer "F.Fab")
		)
		(pad "1" smd rect
			(at -0.40005 0 270)
			(size 0.4572 0.508)
			(layers "F.Cu" "F.Mask" "F.Paste")
			(net "USB2_HOST_BMC_B_DP")
		)
		(pad "2" smd rect
			(at 0.40005 0 270)
			(size 0.4572 0.508)
			(layers "F.Cu" "F.Mask" "F.Paste")
			(net "USB2_HOST_BMC_B_BUF_DP")
		)
	)
)
